(kicad_pcb
	(version 20260206)
	(generator "pcbnew")
	(generator_version "10.0")
	(general
		(thickness 1.6)
		(legacy_teardrops no)
	)
	(paper "A4")
	(title_block
		(title "01162023_DA0F0TEBIF0_F0T_Expander_BD_F_brd_V02_OCP.brd")
		(comment 1 "Grand Teton / footprints 575-581 of 9728")
	)
	(layers
		(0 "F.Cu" signal "TOP")
		(4 "In1.Cu" signal "GND")
		(6 "In2.Cu" signal "VCC")
		(8 "In3.Cu" signal "VCC1")
		(10 "In4.Cu" signal "GND1")
		(12 "In5.Cu" signal "IN1")
		(14 "In6.Cu" signal "GND2")
		(16 "In7.Cu" signal "IN2")
		(18 "In8.Cu" signal "GND3")
		(20 "In9.Cu" signal "IN3")
		(22 "In10.Cu" signal "GND4")
		(24 "In11.Cu" signal "IN4")
		(26 "In12.Cu" signal "GND5")
		(28 "In13.Cu" signal "IN5")
		(30 "In14.Cu" signal "GND6")
		(32 "In15.Cu" signal "IN6")
		(34 "In16.Cu" signal "GND7")
		(2 "B.Cu" signal "BOTTOM")
		(9 "F.Adhes" user "F.Adhesive")
		(11 "B.Adhes" user "B.Adhesive")
		(13 "F.Paste" user "Package Geometry/Pastemask Top")
		(15 "B.Paste" user "Package Geometry/Pastemask Bottom")
		(5 "F.SilkS" user "Ref Des/Silkscreen Top")
		(7 "B.SilkS" user "Ref Des/Silkscreen Bottom")
		(1 "F.Mask" user "Board Geometry/Soldermask Top")
		(3 "B.Mask" user "Board Geometry/Soldermask Bottom")
		(17 "Dwgs.User" user "User.Drawings")
		(19 "Cmts.User" user "User.Comments")
		(21 "Eco1.User" user "User.Eco1")
		(23 "Eco2.User" user "User.Eco2")
		(25 "Edge.Cuts" user "Board Geometry/Outline")
		(27 "Margin" user)
		(31 "F.CrtYd" user "Package Geometry/Place Bound Top")
		(29 "B.CrtYd" user "Package Geometry/Place Bound Bottom")
		(35 "F.Fab" user "Ref Des/Assembly Top")
		(33 "B.Fab" user "Ref Des/Assembly Bottom")
	)
	(footprint ""
		(layer "F.Cu")
		(at 295.72585 -165.670484 -90)
		(property "Reference" "R3309"
			(at 0 0 270)
			(layer "F.SilkS")
			(hide yes)
			(effects
				(font
					(size 1.27 1.27)
				)
			)
		)
		(property "Value" ""
			(at 0 0 270)
			(layer "F.Fab")
			(effects
				(font
					(size 1.27 1.27)
				)
			)
		)
		(duplicate_pad_numbers_are_jumpers no)
		(fp_line
			(start -0.7874 0.4064)
			(end -0.7874 -0.4064)
			(stroke
				(width 0.1524)
				(type default)
			)
			(layer "F.SilkS")
		)
		(fp_line
			(start 0.7874 0.4064)
			(end -0.7874 0.4064)
			(stroke
				(width 0.1524)
				(type default)
			)
			(layer "F.SilkS")
		)
		(fp_line
			(start -0.7874 -0.4064)
			(end 0.7874 -0.4064)
			(stroke
				(width 0.1524)
				(type default)
			)
			(layer "F.SilkS")
		)
		(fp_line
			(start 0.7874 -0.4064)
			(end 0.7874 0.4064)
			(stroke
				(width 0.1524)
				(type default)
			)
			(layer "F.SilkS")
		)
		(fp_line
			(start -0.67945 0.3048)
			(end -0.67945 -0.305054)
			(stroke
				(width 0.1)
				(type default)
			)
			(layer "F.Fab")
		)
		(fp_line
			(start -0.12065 0.3048)
			(end -0.67945 0.3048)
			(stroke
				(width 0.1)
				(type default)
			)
			(layer "F.Fab")
		)
		(fp_line
			(start 0.120396 0.3048)
			(end 0.120396 0.2794)
			(stroke
				(width 0.1)
				(type default)
			)
			(layer "F.Fab")
		)
		(fp_line
			(start 0.67945 0.3048)
			(end 0.120396 0.3048)
			(stroke
				(width 0.1)
				(type default)
			)
			(layer "F.Fab")
		)
		(fp_line
			(start -0.12065 0.2794)
			(end -0.12065 0.3048)
			(stroke
				(width 0.1)
				(type default)
			)
			(layer "F.Fab")
		)
		(fp_line
			(start 0.120396 0.2794)
			(end -0.12065 0.2794)
			(stroke
				(width 0.1)
				(type default)
			)
			(layer "F.Fab")
		)
		(fp_line
			(start -0.12065 -0.2794)
			(end 0.12065 -0.2794)
			(stroke
				(width 0.1)
				(type default)
			)
			(layer "F.Fab")
		)
		(fp_line
			(start 0.12065 -0.2794)
			(end 0.12065 -0.3048)
			(stroke
				(width 0.1)
				(type default)
			)
			(layer "F.Fab")
		)
		(fp_line
			(start 0.12065 -0.3048)
			(end 0.67945 -0.3048)
			(stroke
				(width 0.1)
				(type default)
			)
			(layer "F.Fab")
		)
		(fp_line
			(start 0.67945 -0.3048)
			(end 0.67945 0.3048)
			(stroke
				(width 0.1)
				(type default)
			)
			(layer "F.Fab")
		)
		(fp_line
			(start -0.67945 -0.305054)
			(end -0.12065 -0.305054)
			(stroke
				(width 0.1)
				(type default)
			)
			(layer "F.Fab")
		)
		(fp_line
			(start -0.12065 -0.305054)
			(end -0.12065 -0.2794)
			(stroke
				(width 0.1)
				(type default)
			)
			(layer "F.Fab")
		)
		(pad "1" smd circle
			(at -0.40005 0 270)
			(size 0 0)
			(layers "F.Cu" "F.Mask" "F.Paste")
			(net "FM_SYS_THROTTLE_R")
		)
		(pad "2" smd circle
			(at 0.40005 0 270)
			(size 0 0)
			(layers "F.Cu" "F.Mask" "F.Paste")
			(net "FM_SYS_THROTTLE_NIC5")
		)
	)
	(footprint ""
		(layer "F.Cu")
		(at 110.496096 -92.333572 -90)
		(property "Reference" "R1150"
			(at 0 0 270)
			(layer "F.SilkS")
			(hide yes)
			(effects
				(font
					(size 1.27 1.27)
				)
			)
		)
		(property "Value" ""
			(at 0 0 270)
			(layer "F.Fab")
			(effects
				(font
					(size 1.27 1.27)
				)
			)
		)
		(duplicate_pad_numbers_are_jumpers no)
		(fp_line
			(start -0.7874 -0.4064)
			(end 0.7874 -0.4064)
			(stroke
				(width 0.1524)
				(type default)
			)
			(layer "F.SilkS")
		)
		(fp_line
			(start -0.67945 0.3048)
			(end -0.67945 -0.305054)
			(stroke
				(width 0.1)
				(type default)
			)
			(layer "F.Fab")
		)
		(fp_line
			(start -0.12065 0.3048)
			(end -0.67945 0.3048)
			(stroke
				(width 0.1)
				(type default)
			)
			(layer "F.Fab")
		)
		(fp_line
			(start 0.120396 0.3048)
			(end 0.120396 0.2794)
			(stroke
				(width 0.1)
				(type default)
			)
			(layer "F.Fab")
		)
		(fp_line
			(start 0.67945 0.3048)
			(end 0.120396 0.3048)
			(stroke
				(width 0.1)
				(type default)
			)
			(layer "F.Fab")
		)
		(fp_line
			(start -0.12065 0.2794)
			(end -0.12065 0.3048)
			(stroke
				(width 0.1)
				(type default)
			)
			(layer "F.Fab")
		)
		(fp_line
			(start 0.120396 0.2794)
			(end -0.12065 0.2794)
			(stroke
				(width 0.1)
				(type default)
			)
			(layer "F.Fab")
		)
		(fp_line
			(start -0.12065 -0.2794)
			(end 0.12065 -0.2794)
			(stroke
				(width 0.1)
				(type default)
			)
			(layer "F.Fab")
		)
		(fp_line
			(start 0.12065 -0.2794)
			(end 0.12065 -0.3048)
			(stroke
				(width 0.1)
				(type default)
			)
			(layer "F.Fab")
		)
		(fp_line
			(start 0.12065 -0.3048)
			(end 0.67945 -0.3048)
			(stroke
				(width 0.1)
				(type default)
			)
			(layer "F.Fab")
		)
		(fp_line
			(start 0.67945 -0.3048)
			(end 0.67945 0.3048)
			(stroke
				(width 0.1)
				(type default)
			)
			(layer "F.Fab")
		)
		(fp_line
			(start -0.67945 -0.305054)
			(end -0.12065 -0.305054)
			(stroke
				(width 0.1)
				(type default)
			)
			(layer "F.Fab")
		)
		(fp_line
			(start -0.12065 -0.305054)
			(end -0.12065 -0.2794)
			(stroke
				(width 0.1)
				(type default)
			)
			(layer "F.Fab")
		)
		(pad "1" smd circle
			(at -0.40005 0 270)
			(size 0 0)
			(layers "F.Cu" "F.Mask" "F.Paste")
			(net "CLK_100M_DB800ZL_SSD7_R_DP")
		)
		(pad "2" smd circle
			(at 0.40005 0 270)
			(size 0 0)
			(layers "F.Cu" "F.Mask" "F.Paste")
			(net "CLK_100M_DB800ZL_SSD7_DP")
		)
	)
	(footprint ""
		(layer "F.Cu")
		(at 168.367964 -56.353456)
		(property "Reference" "C2864"
			(at 0 0 0)
			(layer "F.SilkS")
			(hide yes)
			(effects
				(font
					(size 1.27 1.27)
				)
			)
		)
		(property "Value" ""
			(at 0 0 0)
			(layer "F.Fab")
			(effects
				(font
					(size 1.27 1.27)
				)
			)
		)
		(duplicate_pad_numbers_are_jumpers no)
		(fp_line
			(start -0.7874 -0.4064)
			(end 0.7874 -0.4064)
			(stroke
				(width 0.1524)
				(type default)
			)
			(layer "F.SilkS")
		)
		(fp_line
			(start -0.7874 0.4064)
			(end -0.7874 -0.4064)
			(stroke
				(width 0.1524)
				(type default)
			)
			(layer "F.SilkS")
		)
		(fp_line
			(start 0.7874 -0.4064)
			(end 0.7874 0.4064)
			(stroke
				(width 0.1524)
				(type default)
			)
			(layer "F.SilkS")
		)
		(fp_line
			(start 0.7874 0.4064)
			(end -0.7874 0.4064)
			(stroke
				(width 0.1524)
				(type default)
			)
			(layer "F.SilkS")
		)
		(fp_line
			(start -0.67945 -0.305054)
			(end -0.12065 -0.305054)
			(stroke
				(width 0.1)
				(type default)
			)
			(layer "F.Fab")
		)
		(fp_line
			(start -0.67945 0.3048)
			(end -0.67945 -0.305054)
			(stroke
				(width 0.1)
				(type default)
			)
			(layer "F.Fab")
		)
		(fp_line
			(start -0.12065 -0.305054)
			(end -0.12065 -0.2794)
			(stroke
				(width 0.1)
				(type default)
			)
			(layer "F.Fab")
		)
		(fp_line
			(start -0.12065 -0.2794)
			(end 0.12065 -0.2794)
			(stroke
				(width 0.1)
				(type default)
			)
			(layer "F.Fab")
		)
		(fp_line
			(start -0.12065 0.2794)
			(end -0.12065 0.3048)
			(stroke
				(width 0.1)
				(type default)
			)
			(layer "F.Fab")
		)
		(fp_line
			(start -0.12065 0.3048)
			(end -0.67945 0.3048)
			(stroke
				(width 0.1)
				(type default)
			)
			(layer "F.Fab")
		)
		(fp_line
			(start 0.120396 0.2794)
			(end -0.12065 0.2794)
			(stroke
				(width 0.1)
				(type default)
			)
			(layer "F.Fab")
		)
		(fp_line
			(start 0.120396 0.3048)
			(end 0.120396 0.2794)
			(stroke
				(width 0.1)
				(type default)
			)
			(layer "F.Fab")
		)
		(fp_line
			(start 0.12065 -0.3048)
			(end 0.67945 -0.3048)
			(stroke
				(width 0.1)
				(type default)
			)
			(layer "F.Fab")
		)
		(fp_line
			(start 0.12065 -0.2794)
			(end 0.12065 -0.3048)
			(stroke
				(width 0.1)
				(type default)
			)
			(layer "F.Fab")
		)
		(fp_line
			(start 0.67945 -0.3048)
			(end 0.67945 0.3048)
			(stroke
				(width 0.1)
				(type default)
			)
			(layer "F.Fab")
		)
		(fp_line
			(start 0.67945 0.3048)
			(end 0.120396 0.3048)
			(stroke
				(width 0.1)
				(type default)
			)
			(layer "F.Fab")
		)
		(pad "1" smd circle
			(at -0.40005 0)
			(size 0 0)
			(layers "F.Cu" "F.Mask" "F.Paste")
			(net "SSD5_PWR_EN_R")
		)
		(pad "2" smd circle
			(at 0.40005 0)
			(size 0 0)
			(layers "F.Cu" "F.Mask" "F.Paste")
			(net "GND")
		)
	)
	(footprint ""
		(layer "F.Cu")
		(at 448.309746 -254.5969 -90)
		(property "Reference" "C4409"
			(at 0 0 270)
			(layer "F.SilkS")
			(hide yes)
			(effects
				(font
					(size 1.27 1.27)
				)
			)
		)
		(property "Value" ""
			(at 0 0 270)
			(layer "F.Fab")
			(effects
				(font
					(size 1.27 1.27)
				)
			)
		)
		(duplicate_pad_numbers_are_jumpers no)
		(fp_line
			(start -1.2954 0.5842)
			(end -1.2954 -0.5842)
			(stroke
				(width 0.1524)
				(type default)
			)
			(layer "F.SilkS")
		)
		(fp_line
			(start 1.2954 0.5842)
			(end -1.2954 0.5842)
			(stroke
				(width 0.1524)
				(type default)
			)
			(layer "F.SilkS")
		)
		(fp_line
			(start -1.2954 -0.5842)
			(end 1.2954 -0.5842)
			(stroke
				(width 0.1524)
				(type default)
			)
			(layer "F.SilkS")
		)
		(fp_line
			(start 1.2954 -0.5842)
			(end 1.2954 0.5842)
			(stroke
				(width 0.1524)
				(type default)
			)
			(layer "F.SilkS")
		)
		(fp_line
			(start -0.8636 0.4572)
			(end -0.8636 0.4064)
			(stroke
				(width 0.1)
				(type default)
			)
			(layer "F.Fab")
		)
		(fp_line
			(start 0.8636 0.4572)
			(end -0.8636 0.4572)
			(stroke
				(width 0.1)
				(type default)
			)
			(layer "F.Fab")
		)
		(fp_line
			(start -1.1938 0.4064)
			(end -1.1938 -0.4064)
			(stroke
				(width 0.1)
				(type default)
			)
			(layer "F.Fab")
		)
		(fp_line
			(start -0.8636 0.4064)
			(end -1.1938 0.4064)
			(stroke
				(width 0.1)
				(type default)
			)
			(layer "F.Fab")
		)
		(fp_line
			(start 0.8636 0.4064)
			(end 0.8636 0.4572)
			(stroke
				(width 0.1)
				(type default)
			)
			(layer "F.Fab")
		)
		(fp_line
			(start 1.1938 0.4064)
			(end 0.8636 0.4064)
			(stroke
				(width 0.1)
				(type default)
			)
			(layer "F.Fab")
		)
		(fp_line
			(start -1.1938 -0.4064)
			(end -0.8636 -0.4064)
			(stroke
				(width 0.1)
				(type default)
			)
			(layer "F.Fab")
		)
		(fp_line
			(start -0.8636 -0.4064)
			(end -0.8636 -0.4572)
			(stroke
				(width 0.1)
				(type default)
			)
			(layer "F.Fab")
		)
		(fp_line
			(start 0.8636 -0.4064)
			(end 1.1938 -0.4064)
			(stroke
				(width 0.1)
				(type default)
			)
			(layer "F.Fab")
		)
		(fp_line
			(start 1.1938 -0.4064)
			(end 1.1938 0.4064)
			(stroke
				(width 0.1)
				(type default)
			)
			(layer "F.Fab")
		)
		(fp_line
			(start -0.8636 -0.4572)
			(end 0.8636 -0.4572)
			(stroke
				(width 0.1)
				(type default)
			)
			(layer "F.Fab")
		)
		(fp_line
			(start 0.8636 -0.4572)
			(end 0.8636 -0.4064)
			(stroke
				(width 0.1)
				(type default)
			)
			(layer "F.Fab")
		)
		(pad "1" smd rect
			(at -0.7366 0 180)
			(size 0.7112 0.8128)
			(layers "F.Cu" "F.Mask" "F.Paste")
			(net "P1V25_SERDES_VDDPLL_PEX3_C7")
		)
		(pad "2" smd rect
			(at 0.7366 0 180)
			(size 0.7112 0.8128)
			(layers "F.Cu" "F.Mask" "F.Paste")
			(net "GND")
		)
	)
	(footprint ""
		(layer "F.Cu")
		(at 392.919966 -15.649956 180)
		(property "Reference" "H125"
			(at -1.811782 2.60604 0)
			(unlocked yes)
			(layer "B.SilkS")
			(effects
				(font
					(size 0.7874 0.5842)
					(thickness 0.1524)
				)
				(justify left mirror)
			)
		)
		(property "Value" ""
			(at 0 0 180)
			(layer "F.Fab")
			(effects
				(font
					(size 1.27 1.27)
				)
			)
		)
		(duplicate_pad_numbers_are_jumpers no)
		(pad "1" thru_hole rect
			(at 0 0 180)
			(size 4.2164 5.0038)
			(drill 2.0066
				(offset 0.099822 0)
			)
			(layers "*.Cu" "*.Mask")
			(remove_unused_layers no)
			(net "Net_8538")
			(clearance -0.8509)
			(padstack
				(mode front_inner_back)
				(layer "Inner"
					(shape circle)
					(size 4.0132 4.0132)
					(clearance -0.7493)
				)
				(layer "B.Cu"
					(shape circle)
					(size 4.0132 4.0132)
					(clearance -0.7493)
				)
			)
		)
	)
	(footprint ""
		(layer "F.Cu")
		(at 105.287826 -319.545462 90)
		(property "Reference" "L50"
			(at 3.108198 1.49479 0)
			(unlocked yes)
			(layer "F.SilkS")
			(effects
				(font
					(size 0.7874 0.5842)
					(thickness 0.1524)
				)
				(justify left)
			)
		)
		(property "Value" ""
			(at 0 0 90)
			(layer "F.Fab")
			(effects
				(font
					(size 1.27 1.27)
				)
			)
		)
		(duplicate_pad_numbers_are_jumpers no)
		(fp_line
			(start 2.248154 -4.9911)
			(end -2.248154 -4.9911)
			(stroke
				(width 0.1524)
				(type default)
			)
			(layer "F.SilkS")
		)
		(fp_line
			(start -2.248154 -4.9911)
			(end -2.248154 -1.528318)
			(stroke
				(width 0.1524)
				(type default)
			)
			(layer "F.SilkS")
		)
		(fp_line
			(start 2.248154 -1.583436)
			(end 2.248154 -4.9911)
			(stroke
				(width 0.1524)
				(type default)
			)
			(layer "F.SilkS")
		)
		(fp_line
			(start -2.248154 1.59004)
			(end -2.248154 4.9911)
			(stroke
				(width 0.1524)
				(type default)
			)
			(layer "F.SilkS")
		)
		(fp_line
			(start 2.248154 4.9911)
			(end 2.248154 1.480058)
			(stroke
				(width 0.1524)
				(type default)
			)
			(layer "F.SilkS")
		)
		(fp_line
			(start -2.248154 4.9911)
			(end 2.248154 4.9911)
			(stroke
				(width 0.1524)
				(type default)
			)
			(layer "F.SilkS")
		)
		(fp_line
			(start 1.700022 -0.899922)
			(end -1.700022 -0.899922)
			(stroke
				(width 0.1)
				(type default)
			)
			(layer "F.Fab")
		)
		(fp_line
			(start -1.700022 -0.899922)
			(end -1.700022 0.899922)
			(stroke
				(width 0.1)
				(type default)
			)
			(layer "F.Fab")
		)
		(fp_line
			(start 1.700022 0.899922)
			(end 1.700022 -0.899922)
			(stroke
				(width 0.1)
				(type default)
			)
			(layer "F.Fab")
		)
		(fp_line
			(start -1.700022 0.899922)
			(end 1.700022 0.899922)
			(stroke
				(width 0.1)
				(type default)
			)
			(layer "F.Fab")
		)
		(pad "1" smd rect
			(at -1.575054 0 90)
			(size 1.1684 9.8044)
			(layers "F.Cu" "F.Mask" "F.Paste")
			(net "P0V8_PEX0")
		)
		(pad "2" smd rect
			(at 1.575054 0 90)
			(size 1.1684 9.8044)
			(layers "F.Cu" "F.Mask" "F.Paste")
			(net "P0V8_SERDES_VDDA_PEX0")
		)
	)
	(footprint ""
		(layer "F.Cu")
		(at 75.66787 -19.453098)
		(property "Reference" "R1653"
			(at 0 0 0)
			(layer "F.SilkS")
			(hide yes)
			(effects
				(font
					(size 1.27 1.27)
				)
			)
		)
		(property "Value" ""
			(at 0 0 0)
			(layer "F.Fab")
			(effects
				(font
					(size 1.27 1.27)
				)
			)
		)
		(duplicate_pad_numbers_are_jumpers no)
		(fp_line
			(start -0.7874 -0.4064)
			(end 0.7874 -0.4064)
			(stroke
				(width 0.1524)
				(type default)
			)
			(layer "F.SilkS")
		)
		(fp_line
			(start -0.7874 0.4064)
			(end -0.7874 -0.4064)
			(stroke
				(width 0.1524)
				(type default)
			)
			(layer "F.SilkS")
		)
		(fp_line
			(start 0.7874 -0.4064)
			(end 0.7874 0.4064)
			(stroke
				(width 0.1524)
				(type default)
			)
			(layer "F.SilkS")
		)
		(fp_line
			(start 0.7874 0.4064)
			(end -0.7874 0.4064)
			(stroke
				(width 0.1524)
				(type default)
			)
			(layer "F.SilkS")
		)
		(fp_line
			(start -0.67945 -0.305054)
			(end -0.12065 -0.305054)
			(stroke
				(width 0.1)
				(type default)
			)
			(layer "F.Fab")
		)
		(fp_line
			(start -0.67945 0.3048)
			(end -0.67945 -0.305054)
			(stroke
				(width 0.1)
				(type default)
			)
			(layer "F.Fab")
		)
		(fp_line
			(start -0.12065 -0.305054)
			(end -0.12065 -0.2794)
			(stroke
				(width 0.1)
				(type default)
			)
			(layer "F.Fab")
		)
		(fp_line
			(start -0.12065 -0.2794)
			(end 0.12065 -0.2794)
			(stroke
				(width 0.1)
				(type default)
			)
			(layer "F.Fab")
		)
		(fp_line
			(start -0.12065 0.2794)
			(end -0.12065 0.3048)
			(stroke
				(width 0.1)
				(type default)
			)
			(layer "F.Fab")
		)
		(fp_line
			(start -0.12065 0.3048)
			(end -0.67945 0.3048)
			(stroke
				(width 0.1)
				(type default)
			)
			(layer "F.Fab")
		)
		(fp_line
			(start 0.120396 0.2794)
			(end -0.12065 0.2794)
			(stroke
				(width 0.1)
				(type default)
			)
			(layer "F.Fab")
		)
		(fp_line
			(start 0.120396 0.3048)
			(end 0.120396 0.2794)
			(stroke
				(width 0.1)
				(type default)
			)
			(layer "F.Fab")
		)
		(fp_line
			(start 0.12065 -0.3048)
			(end 0.67945 -0.3048)
			(stroke
				(width 0.1)
				(type default)
			)
			(layer "F.Fab")
		)
		(fp_line
			(start 0.12065 -0.2794)
			(end 0.12065 -0.3048)
			(stroke
				(width 0.1)
				(type default)
			)
			(layer "F.Fab")
		)
		(fp_line
			(start 0.67945 -0.3048)
			(end 0.67945 0.3048)
			(stroke
				(width 0.1)
				(type default)
			)
			(layer "F.Fab")
		)
		(fp_line
			(start 0.67945 0.3048)
			(end 0.120396 0.3048)
			(stroke
				(width 0.1)
				(type default)
			)
			(layer "F.Fab")
		)
		(pad "1" smd circle
			(at -0.40005 0)
			(size 0 0)
			(layers "F.Cu" "F.Mask" "F.Paste")
			(net "SMB_ISO_SSD2_R_SDA")
		)
		(pad "2" smd circle
			(at 0.40005 0)
			(size 0 0)
			(layers "F.Cu" "F.Mask" "F.Paste")
			(net "SMB_ISO_SSD2_SDA")
		)
	)
)
